# SCM (Grand Teton) — schematic netlist excerpt (pin names and nets, part order shuffled) for the footprints in the layout excerpt that follows; sources: Cadence DE-HDL packaged netlist, KiCad conversion of 12092022_DA0F0TMDCD0_F0T_Management_Board_D_brd_V3_OCP.brd

PC219  Q_CAP  22UF 16V 20% X6S  pkg C0805  page 52 : A = SW_P3V3_AUX_FLT ; B = GND

U32  74LVC1G17GW  IC  pkg TSSOP5  page 50
  NC  = TP_ID_BUF
  A  = REAR_ID_RST_BTN_N
  GND  = GND
  Y  = ID_RST_BTN_BMC_N
  VCC  = P3V3_AUX

PC260  Q_CAP  1UF 25V 10% X6S  pkg C0402  page 56 : A = P1V0_AUX_VCC ; B = GND

(kicad_pcb
	(version 20260206)
	(generator "pcbnew")
	(generator_version "10.0")
	(general
		(thickness 1.6)
		(legacy_teardrops no)
	)
	(paper "A4")
	(title_block
		(title "12092022_DA0F0TMDCD0_F0T_Management_Board_D_brd_V3_OCP.brd")
		(comment 1 "Grand Teton / footprints 219-221 of 1440")
	)
	(layers
		(0 "F.Cu" signal "TOP")
		(4 "In1.Cu" signal "GND")
		(6 "In2.Cu" signal "IN1")
		(8 "In3.Cu" signal "GND1")
		(10 "In4.Cu" signal "IN2")
		(12 "In5.Cu" signal "VCC")
		(14 "In6.Cu" signal "VCC1")
		(16 "In7.Cu" signal "IN3")
		(18 "In8.Cu" signal "GND2")
		(20 "In9.Cu" signal "IN4")
		(22 "In10.Cu" signal "GND3")
		(2 "B.Cu" signal "BOTTOM")
		(9 "F.Adhes" user "F.Adhesive")
		(11 "B.Adhes" user "B.Adhesive")
		(13 "F.Paste" user "Package Geometry/Pastemask Top")
		(15 "B.Paste" user "Package Geometry/Pastemask Bottom")
		(5 "F.SilkS" user "Ref Des/Silkscreen Top")
		(7 "B.SilkS" user "Ref Des/Silkscreen Bottom")
		(1 "F.Mask" user "Board Geometry/Soldermask Top")
		(3 "B.Mask" user "Board Geometry/Soldermask Bottom")
		(17 "Dwgs.User" user "User.Drawings")
		(19 "Cmts.User" user "User.Comments")
		(21 "Eco1.User" user "User.Eco1")
		(23 "Eco2.User" user "User.Eco2")
		(25 "Edge.Cuts" user "Board Geometry/Outline")
		(27 "Margin" user)
		(31 "F.CrtYd" user "Package Geometry/Place Bound Top")
		(29 "B.CrtYd" user "Package Geometry/Place Bound Bottom")
		(35 "F.Fab" user "Ref Des/Assembly Top")
		(33 "B.Fab" user "Ref Des/Assembly Bottom")
	)
	(footprint ""
		(layer "F.Cu")
		(at 81.6102 -17.907 180)
		(property "Reference" "U32"
			(at 2.101088 1.814322 0)
			(unlocked yes)
			(layer "F.SilkS")
			(effects
				(font
					(size 0.7874 0.5842)
					(thickness 0.1524)
				)
				(justify left)
			)
		)
		(property "Value" ""
			(at 0 0 180)
			(layer "F.Fab")
			(effects
				(font
					(size 1.27 1.27)
				)
			)
		)
		(duplicate_pad_numbers_are_jumpers no)
		(fp_line
			(start 1.695958 1.124966)
			(end -1.695958 1.124966)
			(stroke
				(width 0.1524)
				(type default)
			)
			(layer "F.SilkS")
		)
		(fp_line
			(start 1.695958 -1.124966)
			(end 1.695958 1.124966)
			(stroke
				(width 0.1524)
				(type default)
			)
			(layer "F.SilkS")
		)
		(fp_line
			(start -1.695958 1.124966)
			(end -1.695958 -1.124966)
			(stroke
				(width 0.1524)
				(type default)
			)
			(layer "F.SilkS")
		)
		(fp_line
			(start -1.695958 -1.124966)
			(end 1.695958 -1.124966)
			(stroke
				(width 0.1524)
				(type default)
			)
			(layer "F.SilkS")
		)
		(fp_poly
			(pts
				(xy -0.359918 -2.054352) (xy -0.712216 -1.457452) (xy -0.978154 -2.097278)
			)
			(stroke
				(width 0)
				(type default)
			)
			(fill yes)
			(layer "F.SilkS")
		)
		(fp_line
			(start 0.674878 1.124966)
			(end -0.674878 1.124966)
			(stroke
				(width 0.1)
				(type default)
			)
			(layer "F.Fab")
		)
		(fp_line
			(start 0.674878 -1.124966)
			(end 0.674878 1.124966)
			(stroke
				(width 0.1)
				(type default)
			)
			(layer "F.Fab")
		)
		(fp_line
			(start -0.674878 1.124966)
			(end -0.674878 -1.124966)
			(stroke
				(width 0.1)
				(type default)
			)
			(layer "F.Fab")
		)
		(fp_line
			(start -0.674878 -1.124966)
			(end 0.674878 -1.124966)
			(stroke
				(width 0.1)
				(type default)
			)
			(layer "F.Fab")
		)
		(fp_poly
			(pts
				(xy -2.4892 -0.959866) (xy -1.86944 -0.649986) (xy -2.4892 -0.340106)
			)
			(stroke
				(width 0)
				(type default)
			)
			(fill yes)
			(layer "F.Fab")
		)
		(pad "1" smd rect
			(at -0.94488 -0.649986 270)
			(size 0.3556 1.2446)
			(layers "F.Cu" "F.Mask" "F.Paste")
			(net "TP_ID_BUF")
		)
		(pad "2" smd rect
			(at -0.94488 0 270)
			(size 0.3556 1.2446)
			(layers "F.Cu" "F.Mask" "F.Paste")
			(net "REAR_ID_RST_BTN_N")
		)
		(pad "3" smd rect
			(at -0.94488 0.649986 270)
			(size 0.3556 1.2446)
			(layers "F.Cu" "F.Mask" "F.Paste")
			(net "GND")
		)
		(pad "4" smd rect
			(at 0.94488 0.649986 270)
			(size 0.3556 1.2446)
			(layers "F.Cu" "F.Mask" "F.Paste")
			(net "ID_RST_BTN_BMC_N")
		)
		(pad "5" smd rect
			(at 0.94488 -0.649986 270)
			(size 0.3556 1.2446)
			(layers "F.Cu" "F.Mask" "F.Paste")
			(net "P3V3_AUX")
		)
	)
	(footprint ""
		(layer "F.Cu")
		(at 22.373082 -31.361888 90)
		(property "Reference" "PC260"
			(at 0 0 90)
			(layer "F.SilkS")
			(hide yes)
			(effects
				(font
					(size 1.27 1.27)
				)
			)
		)
		(property "Value" ""
			(at 0 0 90)
			(layer "F.Fab")
			(effects
				(font
					(size 1.27 1.27)
				)
			)
		)
		(duplicate_pad_numbers_are_jumpers no)
		(fp_line
			(start 0.7874 -0.4064)
			(end 0.7874 0.4064)
			(stroke
				(width 0.1524)
				(type default)
			)
			(layer "F.SilkS")
		)
		(fp_line
			(start -0.7874 -0.4064)
			(end 0.7874 -0.4064)
			(stroke
				(width 0.1524)
				(type default)
			)
			(layer "F.SilkS")
		)
		(fp_line
			(start 0.7874 0.4064)
			(end -0.7874 0.4064)
			(stroke
				(width 0.1524)
				(type default)
			)
			(layer "F.SilkS")
		)
		(fp_line
			(start -0.7874 0.4064)
			(end -0.7874 -0.4064)
			(stroke
				(width 0.1524)
				(type default)
			)
			(layer "F.SilkS")
		)
		(fp_line
			(start -0.12065 -0.305054)
			(end -0.12065 -0.2794)
			(stroke
				(width 0.1)
				(type default)
			)
			(layer "F.Fab")
		)
		(fp_line
			(start -0.67945 -0.305054)
			(end -0.12065 -0.305054)
			(stroke
				(width 0.1)
				(type default)
			)
			(layer "F.Fab")
		)
		(fp_line
			(start 0.67945 -0.3048)
			(end 0.67945 0.3048)
			(stroke
				(width 0.1)
				(type default)
			)
			(layer "F.Fab")
		)
		(fp_line
			(start 0.12065 -0.3048)
			(end 0.67945 -0.3048)
			(stroke
				(width 0.1)
				(type default)
			)
			(layer "F.Fab")
		)
		(fp_line
			(start 0.12065 -0.2794)
			(end 0.12065 -0.3048)
			(stroke
				(width 0.1)
				(type default)
			)
			(layer "F.Fab")
		)
		(fp_line
			(start -0.12065 -0.2794)
			(end 0.12065 -0.2794)
			(stroke
				(width 0.1)
				(type default)
			)
			(layer "F.Fab")
		)
		(fp_line
			(start 0.120396 0.2794)
			(end -0.12065 0.2794)
			(stroke
				(width 0.1)
				(type default)
			)
			(layer "F.Fab")
		)
		(fp_line
			(start -0.12065 0.2794)
			(end -0.12065 0.3048)
			(stroke
				(width 0.1)
				(type default)
			)
			(layer "F.Fab")
		)
		(fp_line
			(start 0.67945 0.3048)
			(end 0.120396 0.3048)
			(stroke
				(width 0.1)
				(type default)
			)
			(layer "F.Fab")
		)
		(fp_line
			(start 0.120396 0.3048)
			(end 0.120396 0.2794)
			(stroke
				(width 0.1)
				(type default)
			)
			(layer "F.Fab")
		)
		(fp_line
			(start -0.12065 0.3048)
			(end -0.67945 0.3048)
			(stroke
				(width 0.1)
				(type default)
			)
			(layer "F.Fab")
		)
		(fp_line
			(start -0.67945 0.3048)
			(end -0.67945 -0.305054)
			(stroke
				(width 0.1)
				(type default)
			)
			(layer "F.Fab")
		)
		(pad "1" smd circle
			(at -0.40005 0 90)
			(size 0 0)
			(layers "F.Cu" "F.Mask" "F.Paste")
			(net "P1V0_AUX_VCC")
		)
		(pad "2" smd circle
			(at 0.40005 0 90)
			(size 0 0)
			(layers "F.Cu" "F.Mask" "F.Paste")
			(net "GND")
		)
	)
	(footprint ""
		(layer "F.Cu")
		(at 7.239 -59.309 180)
		(property "Reference" "PC219"
			(at 0 0 180)
			(layer "F.SilkS")
			(hide yes)
			(effects
				(font
					(size 1.27 1.27)
				)
			)
		)
		(property "Value" ""
			(at 0 0 180)
			(layer "F.Fab")
			(effects
				(font
					(size 1.27 1.27)
				)
			)
		)
		(duplicate_pad_numbers_are_jumpers no)
		(fp_line
			(start 1.524 0.762)
			(end -1.524 0.762)
			(stroke
				(width 0.1524)
				(type default)
			)
			(layer "F.SilkS")
		)
		(fp_line
			(start 1.524 -0.762)
			(end 1.524 0.762)
			(stroke
				(width 0.1524)
				(type default)
			)
			(layer "F.SilkS")
		)
		(fp_line
			(start -1.524 0.762)
			(end -1.524 -0.762)
			(stroke
				(width 0.1524)
				(type default)
			)
			(layer "F.SilkS")
		)
		(fp_line
			(start -1.524 -0.762)
			(end 1.524 -0.762)
			(stroke
				(width 0.1524)
				(type default)
			)
			(layer "F.SilkS")
		)
		(fp_line
			(start 1.1049 0.724916)
			(end 1.1049 -0.724916)
			(stroke
				(width 0.1)
				(type default)
			)
			(layer "F.Fab")
		)
		(fp_line
			(start 1.1049 -0.724916)
			(end -1.1049 -0.724916)
			(stroke
				(width 0.1)
				(type default)
			)
			(layer "F.Fab")
		)
		(fp_line
			(start -1.1049 0.724916)
			(end 1.1049 0.724916)
			(stroke
				(width 0.1)
				(type default)
			)
			(layer "F.Fab")
		)
		(fp_line
			(start -1.1049 -0.724916)
			(end -1.1049 0.724916)
			(stroke
				(width 0.1)
				(type default)
			)
			(layer "F.Fab")
		)
		(pad "1" smd rect
			(at -0.889 0)
			(size 1.016 1.27)
			(layers "F.Cu" "F.Mask" "F.Paste")
			(net "SW_P3V3_AUX_FLT")
		)
		(pad "2" smd rect
			(at 0.889 0)
			(size 1.016 1.27)
			(layers "F.Cu" "F.Mask" "F.Paste")
			(net "GND")
		)
	)
)
